(kicad_pcb
	(version 20260206)
	(generator "pcbnew")
	(generator_version "10.0")
	(general
		(thickness 1.6)
		(legacy_teardrops no)
	)
	(paper "A4")
	(title_block
		(title "Wiwynn_Tioga_Pass_MB.brd")
		(comment 1 "Tioga Pass / footprints 4533-4539 of 4770")
	)
	(layers
		(0 "F.Cu" signal "TOP")
		(4 "In1.Cu" signal "L2GND")
		(6 "In2.Cu" signal "L3")
		(8 "In3.Cu" signal "L4GND")
		(10 "In4.Cu" signal "L5")
		(12 "In5.Cu" signal "L6GND")
		(14 "In6.Cu" signal "L7VCC")
		(16 "In7.Cu" signal "L8VCC")
		(18 "In8.Cu" signal "L9GND")
		(20 "In9.Cu" signal "L10")
		(22 "In10.Cu" signal "L11GND")
		(24 "In11.Cu" signal "L12")
		(26 "In12.Cu" signal "L13GND")
		(2 "B.Cu" signal "BOTTOM")
		(9 "F.Adhes" user "F.Adhesive")
		(11 "B.Adhes" user "B.Adhesive")
		(13 "F.Paste" user "Package Geometry/Pastemask Top")
		(15 "B.Paste" user "Package Geometry/Pastemask Bottom")
		(5 "F.SilkS" user "Ref Des/Silkscreen Top")
		(7 "B.SilkS" user "Ref Des/Silkscreen Bottom")
		(1 "F.Mask" user "Board Geometry/Soldermask Top")
		(3 "B.Mask" user "Board Geometry/Soldermask Bottom")
		(17 "Dwgs.User" user "User.Drawings")
		(19 "Cmts.User" user "User.Comments")
		(21 "Eco1.User" user "User.Eco1")
		(23 "Eco2.User" user "User.Eco2")
		(25 "Edge.Cuts" user "Board Geometry/Outline")
		(27 "Margin" user)
		(31 "F.CrtYd" user "Package Geometry/Place Bound Top")
		(29 "B.CrtYd" user "Package Geometry/Place Bound Bottom")
		(35 "F.Fab" user "Ref Des/Assembly Top")
		(33 "B.Fab" user "Ref Des/Assembly Bottom")
	)
	(footprint ""
		(layer "B.Cu")
		(at 496.05438 -128.15062)
		(property "Reference" "C1M3"
			(at 0 0 0)
			(layer "B.SilkS")
			(hide yes)
			(effects
				(font
					(size 1.27 1.27)
				)
				(justify mirror)
			)
		)
		(property "Value" ""
			(at 0 0 0)
			(layer "B.Fab")
			(effects
				(font
					(size 1.27 1.27)
				)
				(justify mirror)
			)
		)
		(duplicate_pad_numbers_are_jumpers no)
		(fp_poly
			(pts
				(xy -0.3048 -0.1016) (xy -0.3048 0.9906) (xy 0.3048 0.9906) (xy 0.3048 -0.1016)
			)
			(stroke
				(width 0)
				(type default)
			)
			(fill no)
			(layer "B.CrtYd")
		)
		(fp_line
			(start -0.3048 -0.1016)
			(end 0.3048 -0.1016)
			(stroke
				(width 0.1)
				(type default)
			)
			(layer "B.Fab")
		)
		(fp_line
			(start -0.3048 0.9906)
			(end -0.3048 -0.1016)
			(stroke
				(width 0.1)
				(type default)
			)
			(layer "B.Fab")
		)
		(fp_line
			(start 0.3048 -0.1016)
			(end 0.3048 0.9906)
			(stroke
				(width 0.1)
				(type default)
			)
			(layer "B.Fab")
		)
		(fp_line
			(start 0.3048 0.9906)
			(end -0.3048 0.9906)
			(stroke
				(width 0.1)
				(type default)
			)
			(layer "B.Fab")
		)
		(pad "1" smd rect
			(at 0 0 180)
			(size 0.508 0.508)
			(layers "B.Cu" "B.Mask" "B.Paste")
			(net "P3V3")
		)
		(pad "2" smd rect
			(at 0 0.889 180)
			(size 0.508 0.508)
			(layers "B.Cu" "B.Mask" "B.Paste")
			(net "GND")
		)
		(zone
			(layer "B.Cu")
			(hatch none 0.5)
			(connect_pads
				(clearance 0)
			)
			(min_thickness 0.25)
			(keepout
				(tracks allowed)
				(vias not_allowed)
				(pads allowed)
				(copperpour not_allowed)
				(footprints allowed)
			)
			(placement
				(enabled no)
				(sheetname "")
			)
			(fill
				(thermal_gap 0.5)
				(thermal_bridge_width 0.5)
				(island_removal_mode 0)
			)
			(polygon
				(pts
					(xy 496.30838 -127.89662) (xy 495.80038 -127.89662) (xy 495.80038 -127.51562) (xy 496.30838 -127.51562)
				)
			)
		)
		(zone
			(layer "B.Cu")
			(hatch none 0.5)
			(connect_pads
				(clearance 0)
			)
			(min_thickness 0.25)
			(keepout
				(tracks not_allowed)
				(vias allowed)
				(pads allowed)
				(copperpour not_allowed)
				(footprints allowed)
			)
			(placement
				(enabled no)
				(sheetname "")
			)
			(fill
				(thermal_gap 0.5)
				(thermal_bridge_width 0.5)
				(island_removal_mode 0)
			)
			(polygon
				(pts
					(xy 496.30838 -127.51562) (xy 495.80038 -127.51562) (xy 495.80038 -127.89662) (xy 496.30838 -127.89662)
				)
			)
		)
	)
	(footprint ""
		(layer "B.Cu")
		(at 471.6653 -124.079 180)
		(property "Reference" "L1M2"
			(at -0.127 -1.07188 180)
			(unlocked yes)
			(layer "B.SilkS")
			(effects
				(font
					(size 0.4064 0.254)
					(thickness 0.1524)
				)
				(justify left mirror)
			)
		)
		(property "Value" ""
			(at 0 0 0)
			(layer "B.Fab")
			(effects
				(font
					(size 1.27 1.27)
				)
				(justify mirror)
			)
		)
		(duplicate_pad_numbers_are_jumpers no)
		(fp_rect
			(start 0.08382 1.09982)
			(end -2.11582 -0.29972)
			(stroke
				(width 0)
				(type default)
			)
			(fill no)
			(layer "B.CrtYd")
		)
		(fp_line
			(start 0.08382 1.09982)
			(end 0.08382 -0.29972)
			(stroke
				(width 0.1)
				(type default)
			)
			(layer "B.Fab")
		)
		(fp_line
			(start 0.08382 -0.29972)
			(end -2.11582 -0.29972)
			(stroke
				(width 0.1)
				(type default)
			)
			(layer "B.Fab")
		)
		(fp_line
			(start -2.11582 1.09982)
			(end 0.08382 1.09982)
			(stroke
				(width 0.1)
				(type default)
			)
			(layer "B.Fab")
		)
		(fp_line
			(start -2.11582 -0.29972)
			(end -2.11582 1.09982)
			(stroke
				(width 0.1)
				(type default)
			)
			(layer "B.Fab")
		)
		(pad "1" smd rect
			(at 0 0)
			(size 1.27 0.508)
			(layers "B.Cu" "B.Mask" "B.Paste")
			(net "USB2_P01_DN")
		)
		(pad "2" smd rect
			(at 0 0.8001)
			(size 1.27 0.508)
			(layers "B.Cu" "B.Mask" "B.Paste")
			(net "USB2_P01_DP")
		)
		(pad "3" smd rect
			(at -2.032 0.8001)
			(size 1.27 0.508)
			(layers "B.Cu" "B.Mask" "B.Paste")
			(net "USB2_P01_ESD_DP")
		)
		(pad "4" smd rect
			(at -2.032 0)
			(size 1.27 0.508)
			(layers "B.Cu" "B.Mask" "B.Paste")
			(net "USB2_P01_ESD_DN")
		)
		(zone
			(layer "B.Cu")
			(hatch none 0.5)
			(connect_pads
				(clearance 0)
			)
			(min_thickness 0.25)
			(keepout
				(tracks not_allowed)
				(vias allowed)
				(pads allowed)
				(copperpour not_allowed)
				(footprints allowed)
			)
			(placement
				(enabled no)
				(sheetname "")
			)
			(fill
				(thermal_gap 0.5)
				(thermal_bridge_width 0.5)
				(island_removal_mode 0)
			)
			(polygon
				(pts
					(xy 471.0303 -124.6251) (xy 471.0303 -124.333) (xy 472.3003 -124.333) (xy 472.3003 -124.6251)
				)
			)
		)
		(zone
			(layer "B.Cu")
			(hatch none 0.5)
			(connect_pads
				(clearance 0)
			)
			(min_thickness 0.25)
			(keepout
				(tracks not_allowed)
				(vias allowed)
				(pads allowed)
				(copperpour not_allowed)
				(footprints allowed)
			)
			(placement
				(enabled no)
				(sheetname "")
			)
			(fill
				(thermal_gap 0.5)
				(thermal_bridge_width 0.5)
				(island_removal_mode 0)
			)
			(polygon
				(pts
					(xy 472.3003 -125.1331) (xy 473.0623 -125.1331) (xy 473.0623 -123.825) (xy 472.3003 -123.825)
				)
			)
		)
		(zone
			(layer "B.Cu")
			(hatch none 0.5)
			(connect_pads
				(clearance 0)
			)
			(min_thickness 0.25)
			(keepout
				(tracks allowed)
				(vias not_allowed)
				(pads allowed)
				(copperpour not_allowed)
				(footprints allowed)
			)
			(placement
				(enabled no)
				(sheetname "")
			)
			(fill
				(thermal_gap 0.5)
				(thermal_bridge_width 0.5)
				(island_removal_mode 0)
			)
			(polygon
				(pts
					(xy 472.3003 -123.825) (xy 472.3003 -125.1331) (xy 473.0623 -125.1331) (xy 473.0623 -123.825)
				)
			)
		)
		(zone
			(layer "B.Cu")
			(hatch none 0.5)
			(connect_pads
				(clearance 0)
			)
			(min_thickness 0.25)
			(keepout
				(tracks not_allowed)
				(vias allowed)
				(pads allowed)
				(copperpour not_allowed)
				(footprints allowed)
			)
			(placement
				(enabled no)
				(sheetname "")
			)
			(fill
				(thermal_gap 0.5)
				(thermal_bridge_width 0.5)
				(island_removal_mode 0)
			)
			(polygon
				(pts
					(xy 473.0623 -124.6251) (xy 473.0623 -124.333) (xy 474.3323 -124.333) (xy 474.3323 -124.6251)
				)
			)
		)
	)
	(footprint ""
		(layer "B.Cu")
		(at 377.589288 -110.817914)
		(property "Reference" "R3N1"
			(at 0 0 0)
			(layer "B.SilkS")
			(hide yes)
			(effects
				(font
					(size 1.27 1.27)
				)
				(justify mirror)
			)
		)
		(property "Value" ""
			(at 0 0 0)
			(layer "B.Fab")
			(effects
				(font
					(size 1.27 1.27)
				)
				(justify mirror)
			)
		)
		(duplicate_pad_numbers_are_jumpers no)
		(fp_poly
			(pts
				(xy 0.2794 -0.1016) (xy -0.2794 -0.1016) (xy -0.2794 0.9906) (xy 0.2794 0.9906)
			)
			(stroke
				(width 0)
				(type default)
			)
			(fill no)
			(layer "B.CrtYd")
		)
		(fp_line
			(start -0.2794 -0.1016)
			(end 0.2794 -0.1016)
			(stroke
				(width 0.1)
				(type default)
			)
			(layer "B.Fab")
		)
		(fp_line
			(start -0.2794 0.9906)
			(end -0.2794 -0.1016)
			(stroke
				(width 0.1)
				(type default)
			)
			(layer "B.Fab")
		)
		(fp_line
			(start 0.2794 -0.1016)
			(end 0.2794 0.9906)
			(stroke
				(width 0.1)
				(type default)
			)
			(layer "B.Fab")
		)
		(fp_line
			(start 0.2794 0.9906)
			(end -0.2794 0.9906)
			(stroke
				(width 0.1)
				(type default)
			)
			(layer "B.Fab")
		)
		(pad "1" smd rect
			(at 0 0 180)
			(size 0.508 0.508)
			(layers "B.Cu" "B.Mask" "B.Paste")
			(net "A_PCH_XCLK_BIASREF")
		)
		(pad "2" smd rect
			(at 0 0.889 180)
			(size 0.508 0.508)
			(layers "B.Cu" "B.Mask" "B.Paste")
			(net "GND")
		)
		(zone
			(layer "B.Cu")
			(hatch none 0.5)
			(connect_pads
				(clearance 0)
			)
			(min_thickness 0.25)
			(keepout
				(tracks allowed)
				(vias not_allowed)
				(pads allowed)
				(copperpour not_allowed)
				(footprints allowed)
			)
			(placement
				(enabled no)
				(sheetname "")
			)
			(fill
				(thermal_gap 0.5)
				(thermal_bridge_width 0.5)
				(island_removal_mode 0)
			)
			(polygon
				(pts
					(xy 377.843288 -110.563914) (xy 377.335288 -110.563914) (xy 377.335288 -110.182914) (xy 377.843288 -110.182914)
				)
			)
		)
		(zone
			(layer "B.Cu")
			(hatch none 0.5)
			(connect_pads
				(clearance 0)
			)
			(min_thickness 0.25)
			(keepout
				(tracks not_allowed)
				(vias allowed)
				(pads allowed)
				(copperpour not_allowed)
				(footprints allowed)
			)
			(placement
				(enabled no)
				(sheetname "")
			)
			(fill
				(thermal_gap 0.5)
				(thermal_bridge_width 0.5)
				(island_removal_mode 0)
			)
			(polygon
				(pts
					(xy 377.843288 -110.182914) (xy 377.335288 -110.182914) (xy 377.335288 -110.563914) (xy 377.843288 -110.563914)
				)
			)
		)
	)
	(footprint ""
		(layer "B.Cu")
		(at 409.702 2.722372)
		(property "Reference" "R2U42"
			(at 0 0 0)
			(layer "B.SilkS")
			(hide yes)
			(effects
				(font
					(size 1.27 1.27)
				)
				(justify mirror)
			)
		)
		(property "Value" ""
			(at 0 0 0)
			(layer "B.Fab")
			(effects
				(font
					(size 1.27 1.27)
				)
				(justify mirror)
			)
		)
		(duplicate_pad_numbers_are_jumpers no)
		(fp_poly
			(pts
				(xy 0.2794 -0.1016) (xy -0.2794 -0.1016) (xy -0.2794 0.9906) (xy 0.2794 0.9906)
			)
			(stroke
				(width 0)
				(type default)
			)
			(fill no)
			(layer "B.CrtYd")
		)
		(fp_line
			(start -0.2794 -0.1016)
			(end 0.2794 -0.1016)
			(stroke
				(width 0.1)
				(type default)
			)
			(layer "B.Fab")
		)
		(fp_line
			(start -0.2794 0.9906)
			(end -0.2794 -0.1016)
			(stroke
				(width 0.1)
				(type default)
			)
			(layer "B.Fab")
		)
		(fp_line
			(start 0.2794 -0.1016)
			(end 0.2794 0.9906)
			(stroke
				(width 0.1)
				(type default)
			)
			(layer "B.Fab")
		)
		(fp_line
			(start 0.2794 0.9906)
			(end -0.2794 0.9906)
			(stroke
				(width 0.1)
				(type default)
			)
			(layer "B.Fab")
		)
		(pad "1" smd rect
			(at 0 0 180)
			(size 0.508 0.508)
			(layers "B.Cu" "B.Mask" "B.Paste")
			(net "FAN_PWM_OUT_SYS0_BUF")
		)
		(pad "2" smd rect
			(at 0 0.889 180)
			(size 0.508 0.508)
			(layers "B.Cu" "B.Mask" "B.Paste")
			(net "FAN_PWM_OUT_SYS0_R")
		)
		(zone
			(layer "B.Cu")
			(hatch none 0.5)
			(connect_pads
				(clearance 0)
			)
			(min_thickness 0.25)
			(keepout
				(tracks allowed)
				(vias not_allowed)
				(pads allowed)
				(copperpour not_allowed)
				(footprints allowed)
			)
			(placement
				(enabled no)
				(sheetname "")
			)
			(fill
				(thermal_gap 0.5)
				(thermal_bridge_width 0.5)
				(island_removal_mode 0)
			)
			(polygon
				(pts
					(xy 409.956 2.976372) (xy 409.448 2.976372) (xy 409.448 3.357372) (xy 409.956 3.357372)
				)
			)
		)
		(zone
			(layer "B.Cu")
			(hatch none 0.5)
			(connect_pads
				(clearance 0)
			)
			(min_thickness 0.25)
			(keepout
				(tracks not_allowed)
				(vias allowed)
				(pads allowed)
				(copperpour not_allowed)
				(footprints allowed)
			)
			(placement
				(enabled no)
				(sheetname "")
			)
			(fill
				(thermal_gap 0.5)
				(thermal_bridge_width 0.5)
				(island_removal_mode 0)
			)
			(polygon
				(pts
					(xy 409.956 3.357372) (xy 409.448 3.357372) (xy 409.448 2.976372) (xy 409.956 2.976372)
				)
			)
		)
	)
	(footprint ""
		(layer "B.Cu")
		(at 357.133398 -77.915516 180)
		(property "Reference" "C3P37"
			(at 0 0 0)
			(layer "B.SilkS")
			(hide yes)
			(effects
				(font
					(size 1.27 1.27)
				)
				(justify mirror)
			)
		)
		(property "Value" ""
			(at 0 0 0)
			(layer "B.Fab")
			(effects
				(font
					(size 1.27 1.27)
				)
				(justify mirror)
			)
		)
		(duplicate_pad_numbers_are_jumpers no)
		(fp_poly
			(pts
				(xy -0.3048 -0.1016) (xy -0.3048 0.9906) (xy 0.3048 0.9906) (xy 0.3048 -0.1016)
			)
			(stroke
				(width 0)
				(type default)
			)
			(fill no)
			(layer "B.CrtYd")
		)
		(fp_line
			(start 0.3048 0.9906)
			(end -0.3048 0.9906)
			(stroke
				(width 0.1)
				(type default)
			)
			(layer "B.Fab")
		)
		(fp_line
			(start 0.3048 -0.1016)
			(end 0.3048 0.9906)
			(stroke
				(width 0.1)
				(type default)
			)
			(layer "B.Fab")
		)
		(fp_line
			(start -0.3048 0.9906)
			(end -0.3048 -0.1016)
			(stroke
				(width 0.1)
				(type default)
			)
			(layer "B.Fab")
		)
		(fp_line
			(start -0.3048 -0.1016)
			(end 0.3048 -0.1016)
			(stroke
				(width 0.1)
				(type default)
			)
			(layer "B.Fab")
		)
		(pad "1" smd rect
			(at 0 0)
			(size 0.508 0.508)
			(layers "B.Cu" "B.Mask" "B.Paste")
			(net "P3E_CPU0_PE1_SS_TXN<6>")
		)
		(pad "2" smd rect
			(at 0 0.889)
			(size 0.508 0.508)
			(layers "B.Cu" "B.Mask" "B.Paste")
			(net "P3E_CPU0_PE1_PCH_TXN<6>")
		)
		(zone
			(layer "B.Cu")
			(hatch none 0.5)
			(connect_pads
				(clearance 0)
			)
			(min_thickness 0.25)
			(keepout
				(tracks not_allowed)
				(vias allowed)
				(pads allowed)
				(copperpour not_allowed)
				(footprints allowed)
			)
			(placement
				(enabled no)
				(sheetname "")
			)
			(fill
				(thermal_gap 0.5)
				(thermal_bridge_width 0.5)
				(island_removal_mode 0)
			)
			(polygon
				(pts
					(xy 356.879398 -78.550516) (xy 357.387398 -78.550516) (xy 357.387398 -78.169516) (xy 356.879398 -78.169516)
				)
			)
		)
		(zone
			(layer "B.Cu")
			(hatch none 0.5)
			(connect_pads
				(clearance 0)
			)
			(min_thickness 0.25)
			(keepout
				(tracks allowed)
				(vias not_allowed)
				(pads allowed)
				(copperpour not_allowed)
				(footprints allowed)
			)
			(placement
				(enabled no)
				(sheetname "")
			)
			(fill
				(thermal_gap 0.5)
				(thermal_bridge_width 0.5)
				(island_removal_mode 0)
			)
			(polygon
				(pts
					(xy 356.879398 -78.169516) (xy 357.387398 -78.169516) (xy 357.387398 -78.550516) (xy 356.879398 -78.550516)
				)
			)
		)
	)
	(footprint ""
		(layer "B.Cu")
		(at 352.8949 -73.5838 -90)
		(property "Reference" "R8D43"
			(at 0 0 90)
			(layer "B.SilkS")
			(hide yes)
			(effects
				(font
					(size 1.27 1.27)
				)
				(justify mirror)
			)
		)
		(property "Value" ""
			(at 0 0 90)
			(layer "B.Fab")
			(effects
				(font
					(size 1.27 1.27)
				)
				(justify mirror)
			)
		)
		(duplicate_pad_numbers_are_jumpers no)
		(fp_poly
			(pts
				(xy 0.2794 -0.1016) (xy -0.2794 -0.1016) (xy -0.2794 0.9906) (xy 0.2794 0.9906)
			)
			(stroke
				(width 0)
				(type default)
			)
			(fill no)
			(layer "B.CrtYd")
		)
		(fp_line
			(start -0.2794 0.9906)
			(end -0.2794 -0.1016)
			(stroke
				(width 0.1)
				(type default)
			)
			(layer "B.Fab")
		)
		(fp_line
			(start 0.2794 0.9906)
			(end -0.2794 0.9906)
			(stroke
				(width 0.1)
				(type default)
			)
			(layer "B.Fab")
		)
		(fp_line
			(start -0.2794 -0.1016)
			(end 0.2794 -0.1016)
			(stroke
				(width 0.1)
				(type default)
			)
			(layer "B.Fab")
		)
		(fp_line
			(start 0.2794 -0.1016)
			(end 0.2794 0.9906)
			(stroke
				(width 0.1)
				(type default)
			)
			(layer "B.Fab")
		)
		(pad "1" smd rect
			(at 0 0 90)
			(size 0.508 0.508)
			(layers "B.Cu" "B.Mask" "B.Paste")
			(net "FM_156M_CPU0_BRD_OSC_EN")
		)
		(pad "2" smd rect
			(at 0 0.889 90)
			(size 0.508 0.508)
			(layers "B.Cu" "B.Mask" "B.Paste")
			(net "FM_CPU0_STL_BRD_OSC_EN")
		)
		(zone
			(layer "B.Cu")
			(hatch none 0.5)
			(connect_pads
				(clearance 0)
			)
			(min_thickness 0.25)
			(keepout
				(tracks not_allowed)
				(vias allowed)
				(pads allowed)
				(copperpour not_allowed)
				(footprints allowed)
			)
			(placement
				(enabled no)
				(sheetname "")
			)
			(fill
				(thermal_gap 0.5)
				(thermal_bridge_width 0.5)
				(island_removal_mode 0)
			)
			(polygon
				(pts
					(xy 352.2599 -73.3298) (xy 352.2599 -73.8378) (xy 352.6409 -73.8378) (xy 352.6409 -73.3298)
				)
			)
		)
		(zone
			(layer "B.Cu")
			(hatch none 0.5)
			(connect_pads
				(clearance 0)
			)
			(min_thickness 0.25)
			(keepout
				(tracks allowed)
				(vias not_allowed)
				(pads allowed)
				(copperpour not_allowed)
				(footprints allowed)
			)
			(placement
				(enabled no)
				(sheetname "")
			)
			(fill
				(thermal_gap 0.5)
				(thermal_bridge_width 0.5)
				(island_removal_mode 0)
			)
			(polygon
				(pts
					(xy 352.6409 -73.3298) (xy 352.6409 -73.8378) (xy 352.2599 -73.8378) (xy 352.2599 -73.3298)
				)
			)
		)
	)
	(footprint ""
		(layer "B.Cu")
		(at 411.1625 -27.813 90)
		(property "Reference" "C25W66"
			(at 0.8382 -0.67818 90)
			(unlocked yes)
			(layer "B.SilkS")
			(effects
				(font
					(size 0.4064 0.254)
					(thickness 0.1524)
				)
				(justify left mirror)
			)
		)
		(property "Value" ""
			(at 0 0 90)
			(layer "B.Fab")
			(effects
				(font
					(size 1.27 1.27)
				)
				(justify mirror)
			)
		)
		(duplicate_pad_numbers_are_jumpers no)
		(fp_poly
			(pts
				(xy -0.3048 -0.1016) (xy -0.3048 0.9906) (xy 0.3048 0.9906) (xy 0.3048 -0.1016)
			)
			(stroke
				(width 0)
				(type default)
			)
			(fill no)
			(layer "B.CrtYd")
		)
		(fp_line
			(start 0.3048 -0.1016)
			(end 0.3048 0.9906)
			(stroke
				(width 0.1)
				(type default)
			)
			(layer "B.Fab")
		)
		(fp_line
			(start -0.3048 -0.1016)
			(end 0.3048 -0.1016)
			(stroke
				(width 0.1)
				(type default)
			)
			(layer "B.Fab")
		)
		(fp_line
			(start 0.3048 0.9906)
			(end -0.3048 0.9906)
			(stroke
				(width 0.1)
				(type default)
			)
			(layer "B.Fab")
		)
		(fp_line
			(start -0.3048 0.9906)
			(end -0.3048 -0.1016)
			(stroke
				(width 0.1)
				(type default)
			)
			(layer "B.Fab")
		)
		(pad "1" smd rect
			(at 0 0 270)
			(size 0.508 0.508)
			(layers "B.Cu" "B.Mask" "B.Paste")
			(net "VCC_VA_3V3")
		)
		(pad "2" smd rect
			(at 0 0.889 270)
			(size 0.508 0.508)
			(layers "B.Cu" "B.Mask" "B.Paste")
			(net "GND")
		)
		(zone
			(layer "B.Cu")
			(hatch none 0.5)
			(connect_pads
				(clearance 0)
			)
			(min_thickness 0.25)
			(keepout
				(tracks allowed)
				(vias not_allowed)
				(pads allowed)
				(copperpour not_allowed)
				(footprints allowed)
			)
			(placement
				(enabled no)
				(sheetname "")
			)
			(fill
				(thermal_gap 0.5)
				(thermal_bridge_width 0.5)
				(island_removal_mode 0)
			)
			(polygon
				(pts
					(xy 411.4165 -28.067) (xy 411.4165 -27.559) (xy 411.7975 -27.559) (xy 411.7975 -28.067)
				)
			)
		)
		(zone
			(layer "B.Cu")
			(hatch none 0.5)
			(connect_pads
				(clearance 0)
			)
			(min_thickness 0.25)
			(keepout
				(tracks not_allowed)
				(vias allowed)
				(pads allowed)
				(copperpour not_allowed)
				(footprints allowed)
			)
			(placement
				(enabled no)
				(sheetname "")
			)
			(fill
				(thermal_gap 0.5)
				(thermal_bridge_width 0.5)
				(island_removal_mode 0)
			)
			(polygon
				(pts
					(xy 411.7975 -28.067) (xy 411.7975 -27.559) (xy 411.4165 -27.559) (xy 411.4165 -28.067)
				)
			)
		)
	)
)
